(kicad_pcb
	(version 20260206)
	(generator "pcbnew")
	(generator_version "10.0")
	(general
		(thickness 1.6)
		(legacy_teardrops no)
	)
	(paper "A4")
	(title_block
		(title "04192023_DAF0TMB3IC0_F0TG_MB_C_brd_V02_OCP.brd")
		(comment 1 "Grand Teton / footprints 5312-5317 of 8354")
	)
	(layers
		(0 "F.Cu" signal "TOP")
		(4 "In1.Cu" signal "GND")
		(6 "In2.Cu" signal "IN1")
		(8 "In3.Cu" signal "GND1")
		(10 "In4.Cu" signal "IN2")
		(12 "In5.Cu" signal "GND2")
		(14 "In6.Cu" signal "IN3")
		(16 "In7.Cu" signal "GND3")
		(18 "In8.Cu" signal "VCC")
		(20 "In9.Cu" signal "VCC1")
		(22 "In10.Cu" signal "GND4")
		(24 "In11.Cu" signal "IN4")
		(26 "In12.Cu" signal "GND5")
		(28 "In13.Cu" signal "IN5")
		(30 "In14.Cu" signal "GND6")
		(32 "In15.Cu" signal "IN6")
		(34 "In16.Cu" signal "GND7")
		(2 "B.Cu" signal "BOTTOM")
		(9 "F.Adhes" user "F.Adhesive")
		(11 "B.Adhes" user "B.Adhesive")
		(13 "F.Paste" user "Package Geometry/Pastemask Top")
		(15 "B.Paste" user "Package Geometry/Pastemask Bottom")
		(5 "F.SilkS" user "Ref Des/Silkscreen Top")
		(7 "B.SilkS" user "Ref Des/Silkscreen Bottom")
		(1 "F.Mask" user "Board Geometry/Soldermask Top")
		(3 "B.Mask" user "Board Geometry/Soldermask Bottom")
		(17 "Dwgs.User" user "User.Drawings")
		(19 "Cmts.User" user "User.Comments")
		(21 "Eco1.User" user "User.Eco1")
		(23 "Eco2.User" user "User.Eco2")
		(25 "Edge.Cuts" user "Board Geometry/Outline")
		(27 "Margin" user)
		(31 "F.CrtYd" user "Package Geometry/Place Bound Top")
		(29 "B.CrtYd" user "Package Geometry/Place Bound Bottom")
		(35 "F.Fab" user "Ref Des/Assembly Top")
		(33 "B.Fab" user "Ref Des/Assembly Bottom")
	)
	(footprint ""
		(layer "B.Cu")
		(at 396.792958 -326.163432)
		(property "Reference" "R1506"
			(at 0 0 0)
			(layer "B.SilkS")
			(hide yes)
			(effects
				(font
					(size 1.27 1.27)
				)
				(justify mirror)
			)
		)
		(property "Value" ""
			(at 0 0 0)
			(layer "B.Fab")
			(effects
				(font
					(size 1.27 1.27)
				)
				(justify mirror)
			)
		)
		(duplicate_pad_numbers_are_jumpers no)
		(fp_line
			(start -0.7874 -0.4064)
			(end -0.7874 0.4064)
			(stroke
				(width 0.1524)
				(type default)
			)
			(layer "B.SilkS")
		)
		(fp_line
			(start -0.7874 0.4064)
			(end 0.7874 0.4064)
			(stroke
				(width 0.1524)
				(type default)
			)
			(layer "B.SilkS")
		)
		(fp_line
			(start 0.7874 -0.4064)
			(end -0.7874 -0.4064)
			(stroke
				(width 0.1524)
				(type default)
			)
			(layer "B.SilkS")
		)
		(fp_line
			(start 0.7874 0.4064)
			(end 0.7874 -0.4064)
			(stroke
				(width 0.1524)
				(type default)
			)
			(layer "B.SilkS")
		)
		(fp_line
			(start -0.67945 -0.3048)
			(end -0.67945 0.3048)
			(stroke
				(width 0.1)
				(type default)
			)
			(layer "B.Fab")
		)
		(fp_line
			(start -0.67945 0.3048)
			(end -0.120396 0.3048)
			(stroke
				(width 0.1)
				(type default)
			)
			(layer "B.Fab")
		)
		(fp_line
			(start -0.12065 -0.3048)
			(end -0.67945 -0.3048)
			(stroke
				(width 0.1)
				(type default)
			)
			(layer "B.Fab")
		)
		(fp_line
			(start -0.12065 -0.2794)
			(end -0.12065 -0.3048)
			(stroke
				(width 0.1)
				(type default)
			)
			(layer "B.Fab")
		)
		(fp_line
			(start -0.120396 0.2794)
			(end 0.12065 0.2794)
			(stroke
				(width 0.1)
				(type default)
			)
			(layer "B.Fab")
		)
		(fp_line
			(start -0.120396 0.3048)
			(end -0.120396 0.2794)
			(stroke
				(width 0.1)
				(type default)
			)
			(layer "B.Fab")
		)
		(fp_line
			(start 0.12065 -0.305054)
			(end 0.12065 -0.2794)
			(stroke
				(width 0.1)
				(type default)
			)
			(layer "B.Fab")
		)
		(fp_line
			(start 0.12065 -0.2794)
			(end -0.12065 -0.2794)
			(stroke
				(width 0.1)
				(type default)
			)
			(layer "B.Fab")
		)
		(fp_line
			(start 0.12065 0.2794)
			(end 0.12065 0.3048)
			(stroke
				(width 0.1)
				(type default)
			)
			(layer "B.Fab")
		)
		(fp_line
			(start 0.12065 0.3048)
			(end 0.67945 0.3048)
			(stroke
				(width 0.1)
				(type default)
			)
			(layer "B.Fab")
		)
		(fp_line
			(start 0.67945 -0.305054)
			(end 0.12065 -0.305054)
			(stroke
				(width 0.1)
				(type default)
			)
			(layer "B.Fab")
		)
		(fp_line
			(start 0.67945 0.3048)
			(end 0.67945 -0.305054)
			(stroke
				(width 0.1)
				(type default)
			)
			(layer "B.Fab")
		)
		(pad "1" smd circle
			(at 0.40005 0 180)
			(size 0 0)
			(layers "B.Cu" "B.Mask" "B.Paste")
			(net "PVDD18_S5_P0")
		)
		(pad "2" smd circle
			(at -0.40005 0 180)
			(size 0 0)
			(layers "B.Cu" "B.Mask" "B.Paste")
			(net "ESPI_CPU0_D3")
		)
	)
	(footprint ""
		(layer "B.Cu")
		(at 106.466386 -264.354564)
		(property "Reference" "C3903"
			(at 0 0 0)
			(layer "B.SilkS")
			(hide yes)
			(effects
				(font
					(size 1.27 1.27)
				)
				(justify mirror)
			)
		)
		(property "Value" ""
			(at 0 0 0)
			(layer "B.Fab")
			(effects
				(font
					(size 1.27 1.27)
				)
				(justify mirror)
			)
		)
		(duplicate_pad_numbers_are_jumpers no)
		(fp_line
			(start -0.7874 -0.4064)
			(end -0.7874 0.4064)
			(stroke
				(width 0.1524)
				(type default)
			)
			(layer "B.SilkS")
		)
		(fp_line
			(start -0.7874 0.4064)
			(end 0.7874 0.4064)
			(stroke
				(width 0.1524)
				(type default)
			)
			(layer "B.SilkS")
		)
		(fp_line
			(start 0.7874 -0.4064)
			(end -0.7874 -0.4064)
			(stroke
				(width 0.1524)
				(type default)
			)
			(layer "B.SilkS")
		)
		(fp_line
			(start 0.7874 0.4064)
			(end 0.7874 -0.4064)
			(stroke
				(width 0.1524)
				(type default)
			)
			(layer "B.SilkS")
		)
		(fp_line
			(start -0.67945 -0.3048)
			(end -0.67945 0.3048)
			(stroke
				(width 0.1)
				(type default)
			)
			(layer "B.Fab")
		)
		(fp_line
			(start -0.67945 0.3048)
			(end -0.120396 0.3048)
			(stroke
				(width 0.1)
				(type default)
			)
			(layer "B.Fab")
		)
		(fp_line
			(start -0.12065 -0.3048)
			(end -0.67945 -0.3048)
			(stroke
				(width 0.1)
				(type default)
			)
			(layer "B.Fab")
		)
		(fp_line
			(start -0.12065 -0.2794)
			(end -0.12065 -0.3048)
			(stroke
				(width 0.1)
				(type default)
			)
			(layer "B.Fab")
		)
		(fp_line
			(start -0.120396 0.2794)
			(end 0.12065 0.2794)
			(stroke
				(width 0.1)
				(type default)
			)
			(layer "B.Fab")
		)
		(fp_line
			(start -0.120396 0.3048)
			(end -0.120396 0.2794)
			(stroke
				(width 0.1)
				(type default)
			)
			(layer "B.Fab")
		)
		(fp_line
			(start 0.12065 -0.305054)
			(end 0.12065 -0.2794)
			(stroke
				(width 0.1)
				(type default)
			)
			(layer "B.Fab")
		)
		(fp_line
			(start 0.12065 -0.2794)
			(end -0.12065 -0.2794)
			(stroke
				(width 0.1)
				(type default)
			)
			(layer "B.Fab")
		)
		(fp_line
			(start 0.12065 0.2794)
			(end 0.12065 0.3048)
			(stroke
				(width 0.1)
				(type default)
			)
			(layer "B.Fab")
		)
		(fp_line
			(start 0.12065 0.3048)
			(end 0.67945 0.3048)
			(stroke
				(width 0.1)
				(type default)
			)
			(layer "B.Fab")
		)
		(fp_line
			(start 0.67945 -0.305054)
			(end 0.12065 -0.305054)
			(stroke
				(width 0.1)
				(type default)
			)
			(layer "B.Fab")
		)
		(fp_line
			(start 0.67945 0.3048)
			(end 0.67945 -0.305054)
			(stroke
				(width 0.1)
				(type default)
			)
			(layer "B.Fab")
		)
		(pad "1" smd circle
			(at 0.40005 0 180)
			(size 0 0)
			(layers "B.Cu" "B.Mask" "B.Paste")
			(net "PVDD11_S3_P1")
		)
		(pad "2" smd circle
			(at -0.40005 0 180)
			(size 0 0)
			(layers "B.Cu" "B.Mask" "B.Paste")
			(net "GND")
		)
	)
	(footprint ""
		(layer "B.Cu")
		(at 86.760304 -328.22388 -90)
		(property "Reference" "PC391"
			(at 9.533636 -0.911606 270)
			(unlocked yes)
			(layer "B.SilkS")
			(effects
				(font
					(size 0.7874 0.5842)
					(thickness 0.1524)
				)
				(justify left mirror)
			)
		)
		(property "Value" ""
			(at 0 0 90)
			(layer "B.Fab")
			(effects
				(font
					(size 1.27 1.27)
				)
				(justify mirror)
			)
		)
		(duplicate_pad_numbers_are_jumpers no)
		(fp_line
			(start -4.533392 2.249932)
			(end 4.533392 2.249932)
			(stroke
				(width 0.1524)
				(type default)
			)
			(layer "B.SilkS")
		)
		(fp_line
			(start 4.533392 2.249932)
			(end 4.533392 -2.249932)
			(stroke
				(width 0.1524)
				(type default)
			)
			(layer "B.SilkS")
		)
		(fp_line
			(start -4.533392 -2.249932)
			(end -4.533392 2.249932)
			(stroke
				(width 0.1524)
				(type default)
			)
			(layer "B.SilkS")
		)
		(fp_line
			(start 4.533392 -2.249932)
			(end -4.533392 -2.249932)
			(stroke
				(width 0.1524)
				(type default)
			)
			(layer "B.SilkS")
		)
		(fp_rect
			(start 5.39242 2.326132)
			(end 4.533392 -2.326132)
			(stroke
				(width 0)
				(type default)
			)
			(fill yes)
			(layer "B.SilkS")
		)
		(fp_line
			(start -3.750056 2.249932)
			(end 3.750056 2.249932)
			(stroke
				(width 0.1)
				(type default)
			)
			(layer "B.Fab")
		)
		(fp_line
			(start 3.750056 2.249932)
			(end 3.750056 -2.249932)
			(stroke
				(width 0.1)
				(type default)
			)
			(layer "B.Fab")
		)
		(fp_line
			(start -3.750056 -2.249932)
			(end -3.750056 2.249932)
			(stroke
				(width 0.1)
				(type default)
			)
			(layer "B.Fab")
		)
		(fp_line
			(start 3.750056 -2.249932)
			(end -3.750056 -2.249932)
			(stroke
				(width 0.1)
				(type default)
			)
			(layer "B.Fab")
		)
		(fp_text user "-"
			(at -4.562348 1.995932 270)
			(unlocked yes)
			(layer "B.SilkS")
			(effects
				(font
					(size 1.905 1.4224)
					(thickness 0.1524)
				)
				(justify left mirror)
			)
		)
		(fp_text user "+"
			(at 6.322314 0.786384 180)
			(unlocked yes)
			(layer "B.SilkS")
			(effects
				(font
					(size 1.905 1.4224)
					(thickness 0.1524)
				)
				(justify left mirror)
			)
		)
		(fp_text user "+"
			(at 6.322314 0.786384 180)
			(unlocked yes)
			(layer "B.Fab")
			(effects
				(font
					(size 1.905 1.4224)
					(thickness 0.1524)
				)
				(justify left mirror)
			)
		)
		(fp_text user "-"
			(at -4.8514 -0.14605 270)
			(unlocked yes)
			(layer "B.Fab")
			(effects
				(font
					(size 1.905 1.4224)
					(thickness 0.1524)
				)
				(justify left mirror)
			)
		)
		(pad "1" smd rect
			(at 3.199892 0 90)
			(size 2.413 2.8194)
			(layers "B.Cu" "B.Mask" "B.Paste")
			(net "PVDDCR_CPU1_P1")
		)
		(pad "2" smd rect
			(at -3.199892 0 90)
			(size 2.413 2.8194)
			(layers "B.Cu" "B.Mask" "B.Paste")
			(net "GND")
		)
	)
	(footprint ""
		(layer "B.Cu")
		(at 252.950726 -321.850004 180)
		(property "Reference" "C1079"
			(at 0 0 0)
			(layer "B.SilkS")
			(hide yes)
			(effects
				(font
					(size 1.27 1.27)
				)
				(justify mirror)
			)
		)
		(property "Value" ""
			(at 0 0 0)
			(layer "B.Fab")
			(effects
				(font
					(size 1.27 1.27)
				)
				(justify mirror)
			)
		)
		(duplicate_pad_numbers_are_jumpers no)
		(fp_line
			(start 0.7874 0.4064)
			(end 0.7874 -0.4064)
			(stroke
				(width 0.1524)
				(type default)
			)
			(layer "B.SilkS")
		)
		(fp_line
			(start 0.7874 -0.4064)
			(end -0.7874 -0.4064)
			(stroke
				(width 0.1524)
				(type default)
			)
			(layer "B.SilkS")
		)
		(fp_line
			(start -0.7874 0.4064)
			(end 0.7874 0.4064)
			(stroke
				(width 0.1524)
				(type default)
			)
			(layer "B.SilkS")
		)
		(fp_line
			(start -0.7874 -0.4064)
			(end -0.7874 0.4064)
			(stroke
				(width 0.1524)
				(type default)
			)
			(layer "B.SilkS")
		)
		(fp_line
			(start 0.67945 0.3048)
			(end 0.67945 -0.305054)
			(stroke
				(width 0.1)
				(type default)
			)
			(layer "B.Fab")
		)
		(fp_line
			(start 0.67945 -0.305054)
			(end 0.12065 -0.305054)
			(stroke
				(width 0.1)
				(type default)
			)
			(layer "B.Fab")
		)
		(fp_line
			(start 0.12065 0.3048)
			(end 0.67945 0.3048)
			(stroke
				(width 0.1)
				(type default)
			)
			(layer "B.Fab")
		)
		(fp_line
			(start 0.12065 0.2794)
			(end 0.12065 0.3048)
			(stroke
				(width 0.1)
				(type default)
			)
			(layer "B.Fab")
		)
		(fp_line
			(start 0.12065 -0.2794)
			(end -0.12065 -0.2794)
			(stroke
				(width 0.1)
				(type default)
			)
			(layer "B.Fab")
		)
		(fp_line
			(start 0.12065 -0.305054)
			(end 0.12065 -0.2794)
			(stroke
				(width 0.1)
				(type default)
			)
			(layer "B.Fab")
		)
		(fp_line
			(start -0.120396 0.3048)
			(end -0.120396 0.2794)
			(stroke
				(width 0.1)
				(type default)
			)
			(layer "B.Fab")
		)
		(fp_line
			(start -0.120396 0.2794)
			(end 0.12065 0.2794)
			(stroke
				(width 0.1)
				(type default)
			)
			(layer "B.Fab")
		)
		(fp_line
			(start -0.12065 -0.2794)
			(end -0.12065 -0.3048)
			(stroke
				(width 0.1)
				(type default)
			)
			(layer "B.Fab")
		)
		(fp_line
			(start -0.12065 -0.3048)
			(end -0.67945 -0.3048)
			(stroke
				(width 0.1)
				(type default)
			)
			(layer "B.Fab")
		)
		(fp_line
			(start -0.67945 0.3048)
			(end -0.120396 0.3048)
			(stroke
				(width 0.1)
				(type default)
			)
			(layer "B.Fab")
		)
		(fp_line
			(start -0.67945 -0.3048)
			(end -0.67945 0.3048)
			(stroke
				(width 0.1)
				(type default)
			)
			(layer "B.Fab")
		)
		(pad "1" smd circle
			(at 0.40005 0)
			(size 0 0)
			(layers "B.Cu" "B.Mask" "B.Paste")
			(net "P1V8_CPU0_RT_1D_ADC_MAM")
		)
		(pad "2" smd circle
			(at -0.40005 0)
			(size 0 0)
			(layers "B.Cu" "B.Mask" "B.Paste")
			(net "GND")
		)
	)
	(footprint ""
		(layer "B.Cu")
		(at 165.018974 -390.560052 90)
		(property "Reference" "C431"
			(at 0 0 90)
			(layer "B.SilkS")
			(hide yes)
			(effects
				(font
					(size 1.27 1.27)
				)
				(justify mirror)
			)
		)
		(property "Value" ""
			(at 0 0 90)
			(layer "B.Fab")
			(effects
				(font
					(size 1.27 1.27)
				)
				(justify mirror)
			)
		)
		(duplicate_pad_numbers_are_jumpers no)
		(fp_line
			(start 0.7874 -0.4064)
			(end -0.7874 -0.4064)
			(stroke
				(width 0.1524)
				(type default)
			)
			(layer "B.SilkS")
		)
		(fp_line
			(start -0.7874 -0.4064)
			(end -0.7874 0.4064)
			(stroke
				(width 0.1524)
				(type default)
			)
			(layer "B.SilkS")
		)
		(fp_line
			(start 0.7874 0.4064)
			(end 0.7874 -0.4064)
			(stroke
				(width 0.1524)
				(type default)
			)
			(layer "B.SilkS")
		)
		(fp_line
			(start -0.7874 0.4064)
			(end 0.7874 0.4064)
			(stroke
				(width 0.1524)
				(type default)
			)
			(layer "B.SilkS")
		)
		(fp_line
			(start 0.67945 -0.305054)
			(end 0.12065 -0.305054)
			(stroke
				(width 0.1)
				(type default)
			)
			(layer "B.Fab")
		)
		(fp_line
			(start 0.12065 -0.305054)
			(end 0.12065 -0.2794)
			(stroke
				(width 0.1)
				(type default)
			)
			(layer "B.Fab")
		)
		(fp_line
			(start -0.12065 -0.3048)
			(end -0.67945 -0.3048)
			(stroke
				(width 0.1)
				(type default)
			)
			(layer "B.Fab")
		)
		(fp_line
			(start -0.67945 -0.3048)
			(end -0.67945 0.3048)
			(stroke
				(width 0.1)
				(type default)
			)
			(layer "B.Fab")
		)
		(fp_line
			(start 0.12065 -0.2794)
			(end -0.12065 -0.2794)
			(stroke
				(width 0.1)
				(type default)
			)
			(layer "B.Fab")
		)
		(fp_line
			(start -0.12065 -0.2794)
			(end -0.12065 -0.3048)
			(stroke
				(width 0.1)
				(type default)
			)
			(layer "B.Fab")
		)
		(fp_line
			(start 0.12065 0.2794)
			(end 0.12065 0.3048)
			(stroke
				(width 0.1)
				(type default)
			)
			(layer "B.Fab")
		)
		(fp_line
			(start -0.120396 0.2794)
			(end 0.12065 0.2794)
			(stroke
				(width 0.1)
				(type default)
			)
			(layer "B.Fab")
		)
		(fp_line
			(start 0.67945 0.3048)
			(end 0.67945 -0.305054)
			(stroke
				(width 0.1)
				(type default)
			)
			(layer "B.Fab")
		)
		(fp_line
			(start 0.12065 0.3048)
			(end 0.67945 0.3048)
			(stroke
				(width 0.1)
				(type default)
			)
			(layer "B.Fab")
		)
		(fp_line
			(start -0.120396 0.3048)
			(end -0.120396 0.2794)
			(stroke
				(width 0.1)
				(type default)
			)
			(layer "B.Fab")
		)
		(fp_line
			(start -0.67945 0.3048)
			(end -0.120396 0.3048)
			(stroke
				(width 0.1)
				(type default)
			)
			(layer "B.Fab")
		)
		(pad "1" smd circle
			(at 0.40005 0 270)
			(size 0 0)
			(layers "B.Cu" "B.Mask" "B.Paste")
			(net "P0V9_CPU1_RT2_2A")
		)
		(pad "2" smd circle
			(at -0.40005 0 270)
			(size 0 0)
			(layers "B.Cu" "B.Mask" "B.Paste")
			(net "GND")
		)
	)
	(footprint ""
		(layer "B.Cu")
		(at 9.838182 -409.472384 90)
		(property "Reference" "PR6548"
			(at 0 0 90)
			(layer "B.SilkS")
			(hide yes)
			(effects
				(font
					(size 1.27 1.27)
				)
				(justify mirror)
			)
		)
		(property "Value" ""
			(at 0 0 90)
			(layer "B.Fab")
			(effects
				(font
					(size 1.27 1.27)
				)
				(justify mirror)
			)
		)
		(duplicate_pad_numbers_are_jumpers no)
		(fp_line
			(start 0.7874 -0.4064)
			(end -0.7874 -0.4064)
			(stroke
				(width 0.1524)
				(type default)
			)
			(layer "B.SilkS")
		)
		(fp_line
			(start -0.7874 -0.4064)
			(end -0.7874 0.4064)
			(stroke
				(width 0.1524)
				(type default)
			)
			(layer "B.SilkS")
		)
		(fp_line
			(start 0.7874 0.4064)
			(end 0.7874 -0.4064)
			(stroke
				(width 0.1524)
				(type default)
			)
			(layer "B.SilkS")
		)
		(fp_line
			(start -0.7874 0.4064)
			(end 0.7874 0.4064)
			(stroke
				(width 0.1524)
				(type default)
			)
			(layer "B.SilkS")
		)
		(fp_line
			(start 0.67945 -0.305054)
			(end 0.12065 -0.305054)
			(stroke
				(width 0.1)
				(type default)
			)
			(layer "B.Fab")
		)
		(fp_line
			(start 0.12065 -0.305054)
			(end 0.12065 -0.2794)
			(stroke
				(width 0.1)
				(type default)
			)
			(layer "B.Fab")
		)
		(fp_line
			(start -0.12065 -0.3048)
			(end -0.67945 -0.3048)
			(stroke
				(width 0.1)
				(type default)
			)
			(layer "B.Fab")
		)
		(fp_line
			(start -0.67945 -0.3048)
			(end -0.67945 0.3048)
			(stroke
				(width 0.1)
				(type default)
			)
			(layer "B.Fab")
		)
		(fp_line
			(start 0.12065 -0.2794)
			(end -0.12065 -0.2794)
			(stroke
				(width 0.1)
				(type default)
			)
			(layer "B.Fab")
		)
		(fp_line
			(start -0.12065 -0.2794)
			(end -0.12065 -0.3048)
			(stroke
				(width 0.1)
				(type default)
			)
			(layer "B.Fab")
		)
		(fp_line
			(start 0.12065 0.2794)
			(end 0.12065 0.3048)
			(stroke
				(width 0.1)
				(type default)
			)
			(layer "B.Fab")
		)
		(fp_line
			(start -0.120396 0.2794)
			(end 0.12065 0.2794)
			(stroke
				(width 0.1)
				(type default)
			)
			(layer "B.Fab")
		)
		(fp_line
			(start 0.67945 0.3048)
			(end 0.67945 -0.305054)
			(stroke
				(width 0.1)
				(type default)
			)
			(layer "B.Fab")
		)
		(fp_line
			(start 0.12065 0.3048)
			(end 0.67945 0.3048)
			(stroke
				(width 0.1)
				(type default)
			)
			(layer "B.Fab")
		)
		(fp_line
			(start -0.120396 0.3048)
			(end -0.120396 0.2794)
			(stroke
				(width 0.1)
				(type default)
			)
			(layer "B.Fab")
		)
		(fp_line
			(start -0.67945 0.3048)
			(end -0.120396 0.3048)
			(stroke
				(width 0.1)
				(type default)
			)
			(layer "B.Fab")
		)
		(pad "1" smd circle
			(at 0.40005 0 270)
			(size 0 0)
			(layers "B.Cu" "B.Mask" "B.Paste")
			(net "P0V9_RETIMER_CPU1_TEMP1_R")
		)
		(pad "2" smd circle
			(at -0.40005 0 270)
			(size 0 0)
			(layers "B.Cu" "B.Mask" "B.Paste")
			(net "GND")
		)
	)
)
